# SCM (Grand Teton) — schematic netlist excerpt (pin names and nets, part order shuffled) for the footprints in the layout excerpt that follows; sources: Cadence DE-HDL packaged netlist, KiCad conversion of 12092022_DA0F0TMDCD0_F0T_Management_Board_D_brd_V3_OCP.brd

R638  Q_RES  33.2 1% CHIP  pkg 0402LF  page 35 : A = RST_BMC_HW_R ; B = RST_BMC_HW
R288  Q_RES  10K 1% CHIP  pkg 0402LF  page 36 : A = VCCIO2 ; B = PU_PB25A

(kicad_pcb
	(version 20260206)
	(generator "pcbnew")
	(generator_version "10.0")
	(general
		(thickness 1.6)
		(legacy_teardrops no)
	)
	(paper "A4")
	(title_block
		(title "12092022_DA0F0TMDCD0_F0T_Management_Board_D_brd_V3_OCP.brd")
		(comment 1 "Grand Teton / footprints 522-523 of 1440")
	)
	(layers
		(0 "F.Cu" signal "TOP")
		(4 "In1.Cu" signal "GND")
		(6 "In2.Cu" signal "IN1")
		(8 "In3.Cu" signal "GND1")
		(10 "In4.Cu" signal "IN2")
		(12 "In5.Cu" signal "VCC")
		(14 "In6.Cu" signal "VCC1")
		(16 "In7.Cu" signal "IN3")
		(18 "In8.Cu" signal "GND2")
		(20 "In9.Cu" signal "IN4")
		(22 "In10.Cu" signal "GND3")
		(2 "B.Cu" signal "BOTTOM")
		(9 "F.Adhes" user "F.Adhesive")
		(11 "B.Adhes" user "B.Adhesive")
		(13 "F.Paste" user "Package Geometry/Pastemask Top")
		(15 "B.Paste" user "Package Geometry/Pastemask Bottom")
		(5 "F.SilkS" user "Ref Des/Silkscreen Top")
		(7 "B.SilkS" user "Ref Des/Silkscreen Bottom")
		(1 "F.Mask" user "Board Geometry/Soldermask Top")
		(3 "B.Mask" user "Board Geometry/Soldermask Bottom")
		(17 "Dwgs.User" user "User.Drawings")
		(19 "Cmts.User" user "User.Comments")
		(21 "Eco1.User" user "User.Eco1")
		(23 "Eco2.User" user "User.Eco2")
		(25 "Edge.Cuts" user "Board Geometry/Outline")
		(27 "Margin" user)
		(31 "F.CrtYd" user "Package Geometry/Place Bound Top")
		(29 "B.CrtYd" user "Package Geometry/Place Bound Bottom")
		(35 "F.Fab" user "Ref Des/Assembly Top")
		(33 "B.Fab" user "Ref Des/Assembly Bottom")
	)
	(footprint ""
		(layer "F.Cu")
		(at 12.319 -96.52 180)
		(property "Reference" "R638"
			(at 0 0 180)
			(layer "F.SilkS")
			(hide yes)
			(effects
				(font
					(size 1.27 1.27)
				)
			)
		)
		(property "Value" ""
			(at 0 0 180)
			(layer "F.Fab")
			(effects
				(font
					(size 1.27 1.27)
				)
			)
		)
		(duplicate_pad_numbers_are_jumpers no)
		(fp_line
			(start 0.7874 0.4064)
			(end -0.7874 0.4064)
			(stroke
				(width 0.1524)
				(type default)
			)
			(layer "F.SilkS")
		)
		(fp_line
			(start 0.7874 -0.4064)
			(end 0.7874 0.4064)
			(stroke
				(width 0.1524)
				(type default)
			)
			(layer "F.SilkS")
		)
		(fp_line
			(start -0.7874 0.4064)
			(end -0.7874 -0.4064)
			(stroke
				(width 0.1524)
				(type default)
			)
			(layer "F.SilkS")
		)
		(fp_line
			(start -0.7874 -0.4064)
			(end 0.7874 -0.4064)
			(stroke
				(width 0.1524)
				(type default)
			)
			(layer "F.SilkS")
		)
		(fp_line
			(start 0.67945 0.3048)
			(end 0.120396 0.3048)
			(stroke
				(width 0.1)
				(type default)
			)
			(layer "F.Fab")
		)
		(fp_line
			(start 0.67945 -0.3048)
			(end 0.67945 0.3048)
			(stroke
				(width 0.1)
				(type default)
			)
			(layer "F.Fab")
		)
		(fp_line
			(start 0.12065 -0.2794)
			(end 0.12065 -0.3048)
			(stroke
				(width 0.1)
				(type default)
			)
			(layer "F.Fab")
		)
		(fp_line
			(start 0.12065 -0.3048)
			(end 0.67945 -0.3048)
			(stroke
				(width 0.1)
				(type default)
			)
			(layer "F.Fab")
		)
		(fp_line
			(start 0.120396 0.3048)
			(end 0.120396 0.2794)
			(stroke
				(width 0.1)
				(type default)
			)
			(layer "F.Fab")
		)
		(fp_line
			(start 0.120396 0.2794)
			(end -0.12065 0.2794)
			(stroke
				(width 0.1)
				(type default)
			)
			(layer "F.Fab")
		)
		(fp_line
			(start -0.12065 0.3048)
			(end -0.67945 0.3048)
			(stroke
				(width 0.1)
				(type default)
			)
			(layer "F.Fab")
		)
		(fp_line
			(start -0.12065 0.2794)
			(end -0.12065 0.3048)
			(stroke
				(width 0.1)
				(type default)
			)
			(layer "F.Fab")
		)
		(fp_line
			(start -0.12065 -0.2794)
			(end 0.12065 -0.2794)
			(stroke
				(width 0.1)
				(type default)
			)
			(layer "F.Fab")
		)
		(fp_line
			(start -0.12065 -0.305054)
			(end -0.12065 -0.2794)
			(stroke
				(width 0.1)
				(type default)
			)
			(layer "F.Fab")
		)
		(fp_line
			(start -0.67945 0.3048)
			(end -0.67945 -0.305054)
			(stroke
				(width 0.1)
				(type default)
			)
			(layer "F.Fab")
		)
		(fp_line
			(start -0.67945 -0.305054)
			(end -0.12065 -0.305054)
			(stroke
				(width 0.1)
				(type default)
			)
			(layer "F.Fab")
		)
		(pad "1" smd circle
			(at -0.40005 0 180)
			(size 0 0)
			(layers "F.Cu" "F.Mask" "F.Paste")
			(net "RST_BMC_HW_R")
		)
		(pad "2" smd circle
			(at 0.40005 0 180)
			(size 0 0)
			(layers "F.Cu" "F.Mask" "F.Paste")
			(net "RST_BMC_HW")
		)
	)
	(footprint ""
		(layer "F.Cu")
		(at 19.05 -102.743 -90)
		(property "Reference" "R288"
			(at 0 0 270)
			(layer "F.SilkS")
			(hide yes)
			(effects
				(font
					(size 1.27 1.27)
				)
			)
		)
		(property "Value" ""
			(at 0 0 270)
			(layer "F.Fab")
			(effects
				(font
					(size 1.27 1.27)
				)
			)
		)
		(duplicate_pad_numbers_are_jumpers no)
		(fp_line
			(start -0.7874 0.4064)
			(end -0.7874 -0.4064)
			(stroke
				(width 0.1524)
				(type default)
			)
			(layer "F.SilkS")
		)
		(fp_line
			(start 0.7874 0.4064)
			(end -0.7874 0.4064)
			(stroke
				(width 0.1524)
				(type default)
			)
			(layer "F.SilkS")
		)
		(fp_line
			(start -0.7874 -0.4064)
			(end 0.7874 -0.4064)
			(stroke
				(width 0.1524)
				(type default)
			)
			(layer "F.SilkS")
		)
		(fp_line
			(start 0.7874 -0.4064)
			(end 0.7874 0.4064)
			(stroke
				(width 0.1524)
				(type default)
			)
			(layer "F.SilkS")
		)
		(fp_line
			(start -0.67945 0.3048)
			(end -0.67945 -0.305054)
			(stroke
				(width 0.1)
				(type default)
			)
			(layer "F.Fab")
		)
		(fp_line
			(start -0.12065 0.3048)
			(end -0.67945 0.3048)
			(stroke
				(width 0.1)
				(type default)
			)
			(layer "F.Fab")
		)
		(fp_line
			(start 0.120396 0.3048)
			(end 0.120396 0.2794)
			(stroke
				(width 0.1)
				(type default)
			)
			(layer "F.Fab")
		)
		(fp_line
			(start 0.67945 0.3048)
			(end 0.120396 0.3048)
			(stroke
				(width 0.1)
				(type default)
			)
			(layer "F.Fab")
		)
		(fp_line
			(start -0.12065 0.2794)
			(end -0.12065 0.3048)
			(stroke
				(width 0.1)
				(type default)
			)
			(layer "F.Fab")
		)
		(fp_line
			(start 0.120396 0.2794)
			(end -0.12065 0.2794)
			(stroke
				(width 0.1)
				(type default)
			)
			(layer "F.Fab")
		)
		(fp_line
			(start -0.12065 -0.2794)
			(end 0.12065 -0.2794)
			(stroke
				(width 0.1)
				(type default)
			)
			(layer "F.Fab")
		)
		(fp_line
			(start 0.12065 -0.2794)
			(end 0.12065 -0.3048)
			(stroke
				(width 0.1)
				(type default)
			)
			(layer "F.Fab")
		)
		(fp_line
			(start 0.12065 -0.3048)
			(end 0.67945 -0.3048)
			(stroke
				(width 0.1)
				(type default)
			)
			(layer "F.Fab")
		)
		(fp_line
			(start 0.67945 -0.3048)
			(end 0.67945 0.3048)
			(stroke
				(width 0.1)
				(type default)
			)
			(layer "F.Fab")
		)
		(fp_line
			(start -0.67945 -0.305054)
			(end -0.12065 -0.305054)
			(stroke
				(width 0.1)
				(type default)
			)
			(layer "F.Fab")
		)
		(fp_line
			(start -0.12065 -0.305054)
			(end -0.12065 -0.2794)
			(stroke
				(width 0.1)
				(type default)
			)
			(layer "F.Fab")
		)
		(pad "1" smd circle
			(at -0.40005 0 270)
			(size 0 0)
			(layers "F.Cu" "F.Mask" "F.Paste")
			(net "VCCIO2")
		)
		(pad "2" smd circle
			(at 0.40005 0 270)
			(size 0 0)
			(layers "F.Cu" "F.Mask" "F.Paste")
			(net "PU_PB25A")
		)
	)
)
